(kicad_pcb
	(version 20260206)
	(generator "pcbnew")
	(generator_version "10.0")
	(general
		(thickness 1.6)
		(legacy_teardrops no)
	)
	(paper "A4")
	(title_block
		(title "Bryce Canyon_R.DPB_16317-1_OCP.brd")
		(comment 1 "Bryce Canyon / footprints 351-357 of 2099")
	)
	(layers
		(0 "F.Cu" signal "TOP")
		(4 "In1.Cu" signal "L2GND")
		(6 "In2.Cu" signal "L3")
		(8 "In3.Cu" signal "L4VCC")
		(10 "In4.Cu" signal "L5VCC")
		(12 "In5.Cu" signal "L6")
		(14 "In6.Cu" signal "L7GND")
		(2 "B.Cu" signal "BOTTOM")
		(9 "F.Adhes" user "F.Adhesive")
		(11 "B.Adhes" user "B.Adhesive")
		(13 "F.Paste" user "Package Geometry/Pastemask Top")
		(15 "B.Paste" user "Package Geometry/Pastemask Bottom")
		(5 "F.SilkS" user "Ref Des/Silkscreen Top")
		(7 "B.SilkS" user "Ref Des/Silkscreen Bottom")
		(1 "F.Mask" user "Board Geometry/Soldermask Top")
		(3 "B.Mask" user "Board Geometry/Soldermask Bottom")
		(17 "Dwgs.User" user "User.Drawings")
		(19 "Cmts.User" user "User.Comments")
		(21 "Eco1.User" user "User.Eco1")
		(23 "Eco2.User" user "User.Eco2")
		(25 "Edge.Cuts" user "Board Geometry/Outline")
		(27 "Margin" user)
		(31 "F.CrtYd" user "Package Geometry/Place Bound Top")
		(29 "B.CrtYd" user "Package Geometry/Place Bound Bottom")
		(35 "F.Fab" user "Ref Des/Assembly Top")
		(33 "B.Fab" user "Ref Des/Assembly Bottom")
	)
	(footprint ""
		(layer "F.Cu")
		(at 280.444448 -350.335342 -90)
		(property "Reference" "R1080"
			(at 0 0 270)
			(layer "F.SilkS")
			(hide yes)
			(effects
				(font
					(size 1.27 1.27)
				)
			)
		)
		(property "Value" "0R2J-2-GP"
			(at 0.064008 -3.993896 270)
			(unlocked yes)
			(layer "F.Fab")
			(hide yes)
			(effects
				(font
					(size 1.016 1.016)
					(thickness 0.1524)
				)
			)
		)
		(property "Device Type" "R402H16"
			(at 0.064008 -5.517896 270)
			(unlocked yes)
			(layer "F.Fab")
			(hide yes)
			(effects
				(font
					(size 1.016 1.016)
					(thickness 0.1524)
				)
			)
		)
		(duplicate_pad_numbers_are_jumpers no)
		(fp_line
			(start -0.508 -0.9398)
			(end -0.508 0.9398)
			(stroke
				(width 0.1524)
				(type default)
			)
			(layer "F.SilkS")
		)
		(fp_line
			(start 0.508 -0.9398)
			(end -0.508 -0.9398)
			(stroke
				(width 0.1524)
				(type default)
			)
			(layer "F.SilkS")
		)
		(fp_rect
			(start -0.508 0.9398)
			(end 0.508 -0.9398)
			(stroke
				(width 0)
				(type default)
			)
			(fill no)
			(layer "F.CrtYd")
		)
		(fp_rect
			(start -0.508 0.9398)
			(end 0.508 -0.9398)
			(stroke
				(width 0)
				(type default)
			)
			(fill no)
			(layer "F.Fab")
		)
		(pad "1" smd custom
			(at 0 -0.4445 270)
			(size 0.1397 0.1397)
			(layers "F.Cu" "F.Mask" "F.Paste")
			(net "MAX31790_B_PWM_ST1")
			(options
				(clearance outline)
				(anchor circle)
			)
			(primitives
				(gr_poly
					(pts
						(arc
							(start -0.1778 -0.2794)
							(mid -0.249642 -0.249642)
							(end -0.2794 -0.1778)
						)
						(arc
							(start -0.2794 0.1778)
							(mid -0.249642 0.249642)
							(end -0.1778 0.2794)
						)
						(arc
							(start 0.1778 0.2794)
							(mid 0.249642 0.249642)
							(end 0.2794 0.1778)
						)
						(arc
							(start 0.2794 -0.1778)
							(mid 0.249642 -0.249642)
							(end 0.1778 -0.2794)
						)
					)
					(width 0)
					(fill yes)
				)
			)
		)
		(pad "2" smd custom
			(at 0 0.4445 270)
			(size 0.1397 0.1397)
			(layers "F.Cu" "F.Mask" "F.Paste")
			(net "GND")
			(options
				(clearance outline)
				(anchor circle)
			)
			(primitives
				(gr_poly
					(pts
						(arc
							(start -0.1778 -0.2794)
							(mid -0.249642 -0.249642)
							(end -0.2794 -0.1778)
						)
						(arc
							(start -0.2794 0.1778)
							(mid -0.249642 0.249642)
							(end -0.1778 0.2794)
						)
						(arc
							(start 0.1778 0.2794)
							(mid 0.249642 0.249642)
							(end 0.2794 0.1778)
						)
						(arc
							(start 0.2794 -0.1778)
							(mid 0.249642 -0.249642)
							(end 0.1778 -0.2794)
						)
					)
					(width 0)
					(fill yes)
				)
			)
		)
	)
	(footprint ""
		(layer "F.Cu")
		(at 23.749 -33.274)
		(property "Reference" "R621"
			(at 0 0 0)
			(layer "F.SilkS")
			(hide yes)
			(effects
				(font
					(size 1.27 1.27)
				)
			)
		)
		(property "Value" "2R6F-GP"
			(at -0.0508 -4.8514 0)
			(unlocked yes)
			(layer "F.Fab")
			(hide yes)
			(effects
				(font
					(size 1.016 1.016)
					(thickness 0.1524)
				)
			)
		)
		(property "Device Type" "R1206H26"
			(at 0 -6.3754 0)
			(unlocked yes)
			(layer "F.Fab")
			(hide yes)
			(effects
				(font
					(size 1.016 1.016)
					(thickness 0.1524)
				)
			)
		)
		(duplicate_pad_numbers_are_jumpers no)
		(fp_line
			(start -1.016 -2.2352)
			(end 1.016 -2.2352)
			(stroke
				(width 0.1524)
				(type default)
			)
			(layer "F.SilkS")
		)
		(fp_line
			(start -1.016 2.2352)
			(end -1.016 -2.2352)
			(stroke
				(width 0.1524)
				(type default)
			)
			(layer "F.SilkS")
		)
		(fp_line
			(start 1.016 -2.2352)
			(end 1.016 2.2352)
			(stroke
				(width 0.1524)
				(type default)
			)
			(layer "F.SilkS")
		)
		(fp_line
			(start 1.016 2.2352)
			(end -1.016 2.2352)
			(stroke
				(width 0.1524)
				(type default)
			)
			(layer "F.SilkS")
		)
		(fp_rect
			(start -1.0922 2.3114)
			(end 1.0922 -2.3114)
			(stroke
				(width 0)
				(type default)
			)
			(fill no)
			(layer "F.CrtYd")
		)
		(fp_poly
			(pts
				(xy -1.0922 -2.3114) (xy 1.0922 -2.3114) (xy 1.0922 2.3114) (xy -1.0922 2.3114)
			)
			(stroke
				(width 0)
				(type default)
			)
			(fill no)
			(layer "F.Fab")
		)
		(pad "1" smd rect
			(at 0 -1.397)
			(size 1.651 1.27)
			(layers "F.Cu" "F.Mask" "F.Paste")
			(net "P5V_HDD24")
		)
		(pad "2" smd rect
			(at 0 1.397)
			(size 1.651 1.27)
			(layers "F.Cu" "F.Mask" "F.Paste")
			(net "5V_PRE_24")
		)
	)
	(footprint ""
		(layer "F.Cu")
		(at 441.416186 -119.178578 -90)
		(property "Reference" "C677"
			(at 0 0 270)
			(layer "F.SilkS")
			(hide yes)
			(effects
				(font
					(size 1.27 1.27)
				)
			)
		)
		(property "Value" "SC1U16V3KX-5GP"
			(at 0 -2.8194 270)
			(unlocked yes)
			(layer "F.Fab")
			(hide yes)
			(effects
				(font
					(size 1.016 1.016)
					(thickness 0.1524)
				)
			)
		)
		(property "Device Type" "C603H36"
			(at 0 -4.3434 270)
			(unlocked yes)
			(layer "F.Fab")
			(hide yes)
			(effects
				(font
					(size 1.016 1.016)
					(thickness 0.1524)
				)
			)
		)
		(duplicate_pad_numbers_are_jumpers no)
		(fp_line
			(start 0.508 0)
			(end -0.508 0)
			(stroke
				(width 0.2032)
				(type default)
			)
			(layer "F.SilkS")
		)
		(fp_rect
			(start -0.5842 1.3335)
			(end 0.5842 -1.3335)
			(stroke
				(width 0)
				(type default)
			)
			(fill no)
			(layer "F.CrtYd")
		)
		(fp_rect
			(start -0.5842 1.3335)
			(end 0.5842 -1.3335)
			(stroke
				(width 0)
				(type default)
			)
			(fill no)
			(layer "F.Fab")
		)
		(pad "1" smd custom
			(at 0 -0.762 270)
			(size 0.2159 0.2159)
			(layers "F.Cu" "F.Mask" "F.Paste")
			(net "P5V_B_4_EN_R")
			(options
				(clearance outline)
				(anchor circle)
			)
			(primitives
				(gr_poly
					(pts
						(arc
							(start -0.3302 -0.4318)
							(mid -0.402042 -0.402042)
							(end -0.4318 -0.3302)
						)
						(arc
							(start -0.4318 0.3302)
							(mid -0.402042 0.402042)
							(end -0.3302 0.4318)
						)
						(arc
							(start 0.3302 0.4318)
							(mid 0.402042 0.402042)
							(end 0.4318 0.3302)
						)
						(arc
							(start 0.4318 -0.3302)
							(mid 0.402042 -0.402042)
							(end 0.3302 -0.4318)
						)
					)
					(width 0)
					(fill yes)
				)
			)
		)
		(pad "2" smd custom
			(at 0 0.762 270)
			(size 0.2159 0.2159)
			(layers "F.Cu" "F.Mask" "F.Paste")
			(net "GND")
			(options
				(clearance outline)
				(anchor circle)
			)
			(primitives
				(gr_poly
					(pts
						(arc
							(start -0.3302 -0.4318)
							(mid -0.402042 -0.402042)
							(end -0.4318 -0.3302)
						)
						(arc
							(start -0.4318 0.3302)
							(mid -0.402042 0.402042)
							(end -0.3302 0.4318)
						)
						(arc
							(start 0.3302 0.4318)
							(mid 0.402042 0.402042)
							(end 0.4318 0.3302)
						)
						(arc
							(start 0.4318 -0.3302)
							(mid 0.402042 -0.402042)
							(end 0.3302 -0.4318)
						)
					)
					(width 0)
					(fill yes)
				)
			)
		)
	)
	(footprint ""
		(layer "F.Cu")
		(at 309.1434 -340.812882 180)
		(property "Reference" "R161"
			(at 0 0 180)
			(layer "F.SilkS")
			(hide yes)
			(effects
				(font
					(size 1.27 1.27)
				)
			)
		)
		(property "Value" "100KR2F-L1-GP"
			(at 0.064008 -3.993896 180)
			(unlocked yes)
			(layer "F.Fab")
			(hide yes)
			(effects
				(font
					(size 1.016 1.016)
					(thickness 0.1524)
				)
			)
		)
		(property "Device Type" "R402H16"
			(at 0.064008 -5.517896 180)
			(unlocked yes)
			(layer "F.Fab")
			(hide yes)
			(effects
				(font
					(size 1.016 1.016)
					(thickness 0.1524)
				)
			)
		)
		(duplicate_pad_numbers_are_jumpers no)
		(fp_line
			(start 0.508 -0.9398)
			(end -0.508 -0.9398)
			(stroke
				(width 0.1524)
				(type default)
			)
			(layer "F.SilkS")
		)
		(fp_line
			(start -0.508 -0.9398)
			(end -0.508 0.9398)
			(stroke
				(width 0.1524)
				(type default)
			)
			(layer "F.SilkS")
		)
		(fp_rect
			(start -0.508 0.9398)
			(end 0.508 -0.9398)
			(stroke
				(width 0)
				(type default)
			)
			(fill no)
			(layer "F.CrtYd")
		)
		(fp_rect
			(start -0.508 0.9398)
			(end 0.508 -0.9398)
			(stroke
				(width 0)
				(type default)
			)
			(fill no)
			(layer "F.Fab")
		)
		(pad "1" smd custom
			(at 0 -0.4445 180)
			(size 0.1397 0.1397)
			(layers "F.Cu" "F.Mask" "F.Paste")
			(net "PWM_SCC_B_ZONE_D")
			(options
				(clearance outline)
				(anchor circle)
			)
			(primitives
				(gr_poly
					(pts
						(arc
							(start -0.1778 -0.2794)
							(mid -0.249642 -0.249642)
							(end -0.2794 -0.1778)
						)
						(arc
							(start -0.2794 0.1778)
							(mid -0.249642 0.249642)
							(end -0.1778 0.2794)
						)
						(arc
							(start 0.1778 0.2794)
							(mid 0.249642 0.249642)
							(end 0.2794 0.1778)
						)
						(arc
							(start 0.2794 -0.1778)
							(mid 0.249642 -0.249642)
							(end 0.1778 -0.2794)
						)
					)
					(width 0)
					(fill yes)
				)
			)
		)
		(pad "2" smd custom
			(at 0 0.4445 180)
			(size 0.1397 0.1397)
			(layers "F.Cu" "F.Mask" "F.Paste")
			(net "GND")
			(options
				(clearance outline)
				(anchor circle)
			)
			(primitives
				(gr_poly
					(pts
						(arc
							(start -0.1778 -0.2794)
							(mid -0.249642 -0.249642)
							(end -0.2794 -0.1778)
						)
						(arc
							(start -0.2794 0.1778)
							(mid -0.249642 0.249642)
							(end -0.1778 0.2794)
						)
						(arc
							(start 0.1778 0.2794)
							(mid 0.249642 0.249642)
							(end 0.2794 0.1778)
						)
						(arc
							(start 0.2794 -0.1778)
							(mid 0.249642 -0.249642)
							(end 0.1778 -0.2794)
						)
					)
					(width 0)
					(fill yes)
				)
			)
		)
	)
	(footprint ""
		(layer "F.Cu")
		(at 86.106 -19.558 90)
		(property "Reference" "R680"
			(at 0 0 90)
			(layer "F.SilkS")
			(hide yes)
			(effects
				(font
					(size 1.27 1.27)
				)
			)
		)
		(property "Value" "4K7R2F-GP"
			(at 0.064008 -3.993896 90)
			(unlocked yes)
			(layer "F.Fab")
			(hide yes)
			(effects
				(font
					(size 1.016 1.016)
					(thickness 0.1524)
				)
			)
		)
		(property "Device Type" "R402H16"
			(at 0.064008 -5.517896 90)
			(unlocked yes)
			(layer "F.Fab")
			(hide yes)
			(effects
				(font
					(size 1.016 1.016)
					(thickness 0.1524)
				)
			)
		)
		(duplicate_pad_numbers_are_jumpers no)
		(fp_line
			(start 0.508 -0.9398)
			(end -0.508 -0.9398)
			(stroke
				(width 0.1524)
				(type default)
			)
			(layer "F.SilkS")
		)
		(fp_line
			(start -0.508 -0.9398)
			(end -0.508 0.9398)
			(stroke
				(width 0.1524)
				(type default)
			)
			(layer "F.SilkS")
		)
		(fp_rect
			(start -0.508 0.9398)
			(end 0.508 -0.9398)
			(stroke
				(width 0)
				(type default)
			)
			(fill no)
			(layer "F.CrtYd")
		)
		(fp_rect
			(start -0.508 0.9398)
			(end 0.508 -0.9398)
			(stroke
				(width 0)
				(type default)
			)
			(fill no)
			(layer "F.Fab")
		)
		(pad "1" smd custom
			(at 0 -0.4445 90)
			(size 0.1397 0.1397)
			(layers "F.Cu" "F.Mask" "F.Paste")
			(net "SW_PWR_R_HDD26")
			(options
				(clearance outline)
				(anchor circle)
			)
			(primitives
				(gr_poly
					(pts
						(arc
							(start -0.1778 -0.2794)
							(mid -0.249642 -0.249642)
							(end -0.2794 -0.1778)
						)
						(arc
							(start -0.2794 0.1778)
							(mid -0.249642 0.249642)
							(end -0.1778 0.2794)
						)
						(arc
							(start 0.1778 0.2794)
							(mid 0.249642 0.249642)
							(end 0.2794 0.1778)
						)
						(arc
							(start 0.2794 -0.1778)
							(mid 0.249642 -0.249642)
							(end 0.1778 -0.2794)
						)
					)
					(width 0)
					(fill yes)
				)
			)
		)
		(pad "2" smd custom
			(at 0 0.4445 90)
			(size 0.1397 0.1397)
			(layers "F.Cu" "F.Mask" "F.Paste")
			(net "GND")
			(options
				(clearance outline)
				(anchor circle)
			)
			(primitives
				(gr_poly
					(pts
						(arc
							(start -0.1778 -0.2794)
							(mid -0.249642 -0.249642)
							(end -0.2794 -0.1778)
						)
						(arc
							(start -0.2794 0.1778)
							(mid -0.249642 0.249642)
							(end -0.1778 0.2794)
						)
						(arc
							(start 0.1778 0.2794)
							(mid 0.249642 0.249642)
							(end 0.2794 0.1778)
						)
						(arc
							(start 0.2794 -0.1778)
							(mid 0.249642 -0.249642)
							(end 0.1778 -0.2794)
						)
					)
					(width 0)
					(fill yes)
				)
			)
		)
	)
	(footprint ""
		(layer "F.Cu")
		(at 456.9714 -19.5072)
		(property "Reference" "R859"
			(at 0 0 0)
			(layer "F.SilkS")
			(hide yes)
			(effects
				(font
					(size 1.27 1.27)
				)
			)
		)
		(property "Value" "4K7R2J-2-GP"
			(at 0.064008 -3.993896 0)
			(unlocked yes)
			(layer "F.Fab")
			(hide yes)
			(effects
				(font
					(size 1.016 1.016)
					(thickness 0.1524)
				)
			)
		)
		(property "Device Type" "R402H16"
			(at 0.064008 -5.517896 0)
			(unlocked yes)
			(layer "F.Fab")
			(hide yes)
			(effects
				(font
					(size 1.016 1.016)
					(thickness 0.1524)
				)
			)
		)
		(duplicate_pad_numbers_are_jumpers no)
		(fp_line
			(start -0.508 -0.9398)
			(end -0.508 0.9398)
			(stroke
				(width 0.1524)
				(type default)
			)
			(layer "F.SilkS")
		)
		(fp_line
			(start 0.508 -0.9398)
			(end -0.508 -0.9398)
			(stroke
				(width 0.1524)
				(type default)
			)
			(layer "F.SilkS")
		)
		(fp_rect
			(start -0.508 0.9398)
			(end 0.508 -0.9398)
			(stroke
				(width 0)
				(type default)
			)
			(fill no)
			(layer "F.CrtYd")
		)
		(fp_rect
			(start -0.508 0.9398)
			(end 0.508 -0.9398)
			(stroke
				(width 0)
				(type default)
			)
			(fill no)
			(layer "F.Fab")
		)
		(pad "1" smd custom
			(at 0 -0.4445)
			(size 0.1397 0.1397)
			(layers "F.Cu" "F.Mask" "F.Paste")
			(net "P12V_B")
			(options
				(clearance outline)
				(anchor circle)
			)
			(primitives
				(gr_poly
					(pts
						(arc
							(start -0.1778 -0.2794)
							(mid -0.249642 -0.249642)
							(end -0.2794 -0.1778)
						)
						(arc
							(start -0.2794 0.1778)
							(mid -0.249642 0.249642)
							(end -0.1778 0.2794)
						)
						(arc
							(start 0.1778 0.2794)
							(mid 0.249642 0.249642)
							(end 0.2794 0.1778)
						)
						(arc
							(start 0.2794 -0.1778)
							(mid 0.249642 -0.249642)
							(end 0.1778 -0.2794)
						)
					)
					(width 0)
					(fill yes)
				)
			)
		)
		(pad "2" smd custom
			(at 0 0.4445)
			(size 0.1397 0.1397)
			(layers "F.Cu" "F.Mask" "F.Paste")
			(net "SW_HDD_P34")
			(options
				(clearance outline)
				(anchor circle)
			)
			(primitives
				(gr_poly
					(pts
						(arc
							(start -0.1778 -0.2794)
							(mid -0.249642 -0.249642)
							(end -0.2794 -0.1778)
						)
						(arc
							(start -0.2794 0.1778)
							(mid -0.249642 0.249642)
							(end -0.1778 0.2794)
						)
						(arc
							(start 0.1778 0.2794)
							(mid 0.249642 0.249642)
							(end 0.2794 0.1778)
						)
						(arc
							(start 0.2794 -0.1778)
							(mid 0.249642 -0.249642)
							(end 0.1778 -0.2794)
						)
					)
					(width 0)
					(fill yes)
				)
			)
		)
	)
	(footprint ""
		(layer "F.Cu")
		(at 13.959586 -99.886262 90)
		(property "Reference" "Q255"
			(at 0 0 90)
			(layer "F.SilkS")
			(hide yes)
			(effects
				(font
					(size 1.27 1.27)
				)
			)
		)
		(property "Value" "SSM3K324R-GP"
			(at 0.127 -8.9662 90)
			(unlocked yes)
			(layer "F.Fab")
			(hide yes)
			(effects
				(font
					(size 1.016 1.016)
					(thickness 0.1524)
				)
			)
		)
		(property "Device Type" "SOT23DGS2D4H35"
			(at 0.127 -10.4902 90)
			(unlocked yes)
			(layer "F.Fab")
			(hide yes)
			(effects
				(font
					(size 1.016 1.016)
					(thickness 0.1524)
				)
			)
		)
		(duplicate_pad_numbers_are_jumpers no)
		(fp_line
			(start 1.651 -1.778)
			(end -1.651 -1.778)
			(stroke
				(width 0.1524)
				(type default)
			)
			(layer "F.SilkS")
		)
		(fp_line
			(start -1.651 -1.778)
			(end -1.651 1.778)
			(stroke
				(width 0.1524)
				(type default)
			)
			(layer "F.SilkS")
		)
		(fp_line
			(start 1.651 1.778)
			(end 1.651 -1.778)
			(stroke
				(width 0.1524)
				(type default)
			)
			(layer "F.SilkS")
		)
		(fp_line
			(start -1.651 1.778)
			(end 1.651 1.778)
			(stroke
				(width 0.1524)
				(type default)
			)
			(layer "F.SilkS")
		)
		(fp_poly
			(pts
				(xy -1.778 1.8796) (xy -1.778 -1.8796) (xy 1.778 -1.8796) (xy 1.778 1.8796)
			)
			(stroke
				(width 0)
				(type default)
			)
			(fill no)
			(layer "F.CrtYd")
		)
		(fp_poly
			(pts
				(xy -1.778 1.8796) (xy -1.778 -1.8796) (xy 1.778 -1.8796) (xy 1.778 1.8796)
			)
			(stroke
				(width 0)
				(type default)
			)
			(fill no)
			(layer "F.Fab")
		)
		(pad "D" smd custom
			(at 0 -0.9525 90)
			(size 0.1905 0.1905)
			(layers "F.Cu" "F.Mask" "F.Paste")
			(net "DRV_ACT_12_N")
			(options
				(clearance outline)
				(anchor circle)
			)
			(primitives
				(gr_poly
					(pts
						(arc
							(start -0.1778 0.5715)
							(mid -0.321484 0.511984)
							(end -0.381 0.3683)
						)
						(arc
							(start -0.381 -0.3683)
							(mid -0.321484 -0.511984)
							(end -0.1778 -0.5715)
						)
						(arc
							(start 0.1778 -0.5715)
							(mid 0.321484 -0.511984)
							(end 0.381 -0.3683)
						)
						(arc
							(start 0.381 0.3683)
							(mid 0.321484 0.511984)
							(end 0.1778 0.5715)
						)
					)
					(width 0)
					(fill yes)
				)
			)
		)
		(pad "G" smd custom
			(at -0.98425 0.9525 90)
			(size 0.1905 0.1905)
			(layers "F.Cu" "F.Mask" "F.Paste")
			(net "DRIVE_B_12_ACT")
			(options
				(clearance outline)
				(anchor circle)
			)
			(primitives
				(gr_poly
					(pts
						(arc
							(start -0.1778 0.5715)
							(mid -0.321484 0.511984)
							(end -0.381 0.3683)
						)
						(arc
							(start -0.381 -0.3683)
							(mid -0.321484 -0.511984)
							(end -0.1778 -0.5715)
						)
						(arc
							(start 0.1778 -0.5715)
							(mid 0.321484 -0.511984)
							(end 0.381 -0.3683)
						)
						(arc
							(start 0.381 0.3683)
							(mid 0.321484 0.511984)
							(end 0.1778 0.5715)
						)
					)
					(width 0)
					(fill yes)
				)
			)
		)
		(pad "S" smd custom
			(at 0.98425 0.9525 90)
			(size 0.1905 0.1905)
			(layers "F.Cu" "F.Mask" "F.Paste")
			(net "GND")
			(options
				(clearance outline)
				(anchor circle)
			)
			(primitives
				(gr_poly
					(pts
						(arc
							(start -0.1778 0.5715)
							(mid -0.321484 0.511984)
							(end -0.381 0.3683)
						)
						(arc
							(start -0.381 -0.3683)
							(mid -0.321484 -0.511984)
							(end -0.1778 -0.5715)
						)
						(arc
							(start 0.1778 -0.5715)
							(mid 0.321484 -0.511984)
							(end 0.381 -0.3683)
						)
						(arc
							(start 0.381 0.3683)
							(mid 0.321484 0.511984)
							(end 0.1778 0.5715)
						)
					)
					(width 0)
					(fill yes)
				)
			)
		)
	)
)
